(kicad_pcb
	(version 20260206)
	(generator "pcbnew")
	(generator_version "10.0")
	(general
		(thickness 1.6)
		(legacy_teardrops no)
	)
	(paper "A4")
	(title_block
		(title "Wiwynn_Tioga_Pass_MB.brd")
		(comment 1 "Tioga Pass / footprints 462-466 of 4770")
	)
	(layers
		(0 "F.Cu" signal "TOP")
		(4 "In1.Cu" signal "L2GND")
		(6 "In2.Cu" signal "L3")
		(8 "In3.Cu" signal "L4GND")
		(10 "In4.Cu" signal "L5")
		(12 "In5.Cu" signal "L6GND")
		(14 "In6.Cu" signal "L7VCC")
		(16 "In7.Cu" signal "L8VCC")
		(18 "In8.Cu" signal "L9GND")
		(20 "In9.Cu" signal "L10")
		(22 "In10.Cu" signal "L11GND")
		(24 "In11.Cu" signal "L12")
		(26 "In12.Cu" signal "L13GND")
		(2 "B.Cu" signal "BOTTOM")
		(9 "F.Adhes" user "F.Adhesive")
		(11 "B.Adhes" user "B.Adhesive")
		(13 "F.Paste" user "Package Geometry/Pastemask Top")
		(15 "B.Paste" user "Package Geometry/Pastemask Bottom")
		(5 "F.SilkS" user "Ref Des/Silkscreen Top")
		(7 "B.SilkS" user "Ref Des/Silkscreen Bottom")
		(1 "F.Mask" user "Board Geometry/Soldermask Top")
		(3 "B.Mask" user "Board Geometry/Soldermask Bottom")
		(17 "Dwgs.User" user "User.Drawings")
		(19 "Cmts.User" user "User.Comments")
		(21 "Eco1.User" user "User.Eco1")
		(23 "Eco2.User" user "User.Eco2")
		(25 "Edge.Cuts" user "Board Geometry/Outline")
		(27 "Margin" user)
		(31 "F.CrtYd" user "Package Geometry/Place Bound Top")
		(29 "B.CrtYd" user "Package Geometry/Place Bound Bottom")
		(35 "F.Fab" user "Ref Des/Assembly Top")
		(33 "B.Fab" user "Ref Des/Assembly Bottom")
	)
	(footprint ""
		(layer "F.Cu")
		(at 457.0095 -30.48 90)
		(property "Reference" "R9F52"
			(at 0 0 90)
			(layer "F.SilkS")
			(hide yes)
			(effects
				(font
					(size 1.27 1.27)
				)
			)
		)
		(property "Value" ""
			(at 0 0 90)
			(layer "F.Fab")
			(effects
				(font
					(size 1.27 1.27)
				)
			)
		)
		(duplicate_pad_numbers_are_jumpers no)
		(fp_poly
			(pts
				(xy -0.2794 -0.1016) (xy 0.2794 -0.1016) (xy 0.2794 0.9906) (xy -0.2794 0.9906)
			)
			(stroke
				(width 0)
				(type default)
			)
			(fill no)
			(layer "F.CrtYd")
		)
		(fp_line
			(start 0.2794 -0.1016)
			(end -0.2794 -0.1016)
			(stroke
				(width 0.1)
				(type default)
			)
			(layer "F.Fab")
		)
		(fp_line
			(start -0.2794 -0.1016)
			(end -0.2794 0.9906)
			(stroke
				(width 0.1)
				(type default)
			)
			(layer "F.Fab")
		)
		(fp_line
			(start 0.2794 0.9906)
			(end 0.2794 -0.1016)
			(stroke
				(width 0.1)
				(type default)
			)
			(layer "F.Fab")
		)
		(fp_line
			(start -0.2794 0.9906)
			(end 0.2794 0.9906)
			(stroke
				(width 0.1)
				(type default)
			)
			(layer "F.Fab")
		)
		(pad "1" smd rect
			(at 0 0 90)
			(size 0.508 0.508)
			(layers "F.Cu" "F.Mask" "F.Paste")
			(net "P3V3_STBY")
		)
		(pad "2" smd rect
			(at 0 0.889 90)
			(size 0.508 0.508)
			(layers "F.Cu" "F.Mask" "F.Paste")
			(net "FM_BMC_FAULT_LED")
		)
		(zone
			(layer "F.Cu")
			(hatch none 0.5)
			(connect_pads
				(clearance 0)
			)
			(min_thickness 0.25)
			(keepout
				(tracks allowed)
				(vias not_allowed)
				(pads allowed)
				(copperpour not_allowed)
				(footprints allowed)
			)
			(placement
				(enabled no)
				(sheetname "")
			)
			(fill
				(thermal_gap 0.5)
				(thermal_bridge_width 0.5)
				(island_removal_mode 0)
			)
			(polygon
				(pts
					(xy 457.2635 -30.226) (xy 457.2635 -30.734) (xy 457.6445 -30.734) (xy 457.6445 -30.226)
				)
			)
		)
		(zone
			(layer "F.Cu")
			(hatch none 0.5)
			(connect_pads
				(clearance 0)
			)
			(min_thickness 0.25)
			(keepout
				(tracks not_allowed)
				(vias allowed)
				(pads allowed)
				(copperpour not_allowed)
				(footprints allowed)
			)
			(placement
				(enabled no)
				(sheetname "")
			)
			(fill
				(thermal_gap 0.5)
				(thermal_bridge_width 0.5)
				(island_removal_mode 0)
			)
			(polygon
				(pts
					(xy 457.6445 -30.226) (xy 457.6445 -30.734) (xy 457.2635 -30.734) (xy 457.2635 -30.226)
				)
			)
		)
	)
	(footprint ""
		(layer "F.Cu")
		(at 339.222588 -119.211598 90)
		(property "Reference" "C6B17"
			(at -0.8382 -0.67818 90)
			(unlocked yes)
			(layer "F.SilkS")
			(effects
				(font
					(size 0.4064 0.254)
					(thickness 0.1524)
				)
				(justify left)
			)
		)
		(property "Value" ""
			(at 0 0 90)
			(layer "F.Fab")
			(effects
				(font
					(size 1.27 1.27)
				)
			)
		)
		(duplicate_pad_numbers_are_jumpers no)
		(fp_poly
			(pts
				(xy 0.3048 -0.1016) (xy 0.3048 0.9906) (xy -0.3048 0.9906) (xy -0.3048 -0.1016)
			)
			(stroke
				(width 0)
				(type default)
			)
			(fill no)
			(layer "F.CrtYd")
		)
		(fp_line
			(start 0.3048 -0.1016)
			(end -0.3048 -0.1016)
			(stroke
				(width 0.1)
				(type default)
			)
			(layer "F.Fab")
		)
		(fp_line
			(start -0.3048 -0.1016)
			(end -0.3048 0.9906)
			(stroke
				(width 0.1)
				(type default)
			)
			(layer "F.Fab")
		)
		(fp_line
			(start 0.3048 0.9906)
			(end 0.3048 -0.1016)
			(stroke
				(width 0.1)
				(type default)
			)
			(layer "F.Fab")
		)
		(fp_line
			(start -0.3048 0.9906)
			(end 0.3048 0.9906)
			(stroke
				(width 0.1)
				(type default)
			)
			(layer "F.Fab")
		)
		(pad "1" smd rect
			(at 0 0 90)
			(size 0.508 0.508)
			(layers "F.Cu" "F.Mask" "F.Paste")
			(net "P3E_CPU0_PE1_PCH_TXN<9>")
		)
		(pad "2" smd rect
			(at 0 0.889 90)
			(size 0.508 0.508)
			(layers "F.Cu" "F.Mask" "F.Paste")
			(net "P3E_CPU0_PE1_PCH_C_TXN<9>")
		)
		(zone
			(layer "F.Cu")
			(hatch none 0.5)
			(connect_pads
				(clearance 0)
			)
			(min_thickness 0.25)
			(keepout
				(tracks allowed)
				(vias not_allowed)
				(pads allowed)
				(copperpour not_allowed)
				(footprints allowed)
			)
			(placement
				(enabled no)
				(sheetname "")
			)
			(fill
				(thermal_gap 0.5)
				(thermal_bridge_width 0.5)
				(island_removal_mode 0)
			)
			(polygon
				(pts
					(xy 339.476588 -118.957598) (xy 339.476588 -119.465598) (xy 339.857588 -119.465598) (xy 339.857588 -118.957598)
				)
			)
		)
		(zone
			(layer "F.Cu")
			(hatch none 0.5)
			(connect_pads
				(clearance 0)
			)
			(min_thickness 0.25)
			(keepout
				(tracks not_allowed)
				(vias allowed)
				(pads allowed)
				(copperpour not_allowed)
				(footprints allowed)
			)
			(placement
				(enabled no)
				(sheetname "")
			)
			(fill
				(thermal_gap 0.5)
				(thermal_bridge_width 0.5)
				(island_removal_mode 0)
			)
			(polygon
				(pts
					(xy 339.857588 -118.957598) (xy 339.857588 -119.465598) (xy 339.476588 -119.465598) (xy 339.476588 -118.957598)
				)
			)
		)
	)
	(footprint ""
		(layer "F.Cu")
		(at 369.2906 -100.2284 180)
		(property "Reference" "C7C13"
			(at 0 0 180)
			(layer "F.SilkS")
			(hide yes)
			(effects
				(font
					(size 1.27 1.27)
				)
			)
		)
		(property "Value" ""
			(at 0 0 180)
			(layer "F.Fab")
			(effects
				(font
					(size 1.27 1.27)
				)
			)
		)
		(duplicate_pad_numbers_are_jumpers no)
		(fp_poly
			(pts
				(xy 0.3048 -0.1016) (xy 0.3048 0.9906) (xy -0.3048 0.9906) (xy -0.3048 -0.1016)
			)
			(stroke
				(width 0)
				(type default)
			)
			(fill no)
			(layer "F.CrtYd")
		)
		(fp_line
			(start 0.3048 0.9906)
			(end 0.3048 -0.1016)
			(stroke
				(width 0.1)
				(type default)
			)
			(layer "F.Fab")
		)
		(fp_line
			(start 0.3048 -0.1016)
			(end -0.3048 -0.1016)
			(stroke
				(width 0.1)
				(type default)
			)
			(layer "F.Fab")
		)
		(fp_line
			(start -0.3048 0.9906)
			(end 0.3048 0.9906)
			(stroke
				(width 0.1)
				(type default)
			)
			(layer "F.Fab")
		)
		(fp_line
			(start -0.3048 -0.1016)
			(end -0.3048 0.9906)
			(stroke
				(width 0.1)
				(type default)
			)
			(layer "F.Fab")
		)
		(pad "1" smd rect
			(at 0 0 180)
			(size 0.508 0.508)
			(layers "F.Cu" "F.Mask" "F.Paste")
			(net "XTAL_33K_RTC1")
		)
		(pad "2" smd rect
			(at 0 0.889 180)
			(size 0.508 0.508)
			(layers "F.Cu" "F.Mask" "F.Paste")
			(net "GND")
		)
		(zone
			(layer "F.Cu")
			(hatch none 0.5)
			(connect_pads
				(clearance 0)
			)
			(min_thickness 0.25)
			(keepout
				(tracks not_allowed)
				(vias allowed)
				(pads allowed)
				(copperpour not_allowed)
				(footprints allowed)
			)
			(placement
				(enabled no)
				(sheetname "")
			)
			(fill
				(thermal_gap 0.5)
				(thermal_bridge_width 0.5)
				(island_removal_mode 0)
			)
			(polygon
				(pts
					(xy 369.5446 -100.8634) (xy 369.0366 -100.8634) (xy 369.0366 -100.4824) (xy 369.5446 -100.4824)
				)
			)
		)
		(zone
			(layer "F.Cu")
			(hatch none 0.5)
			(connect_pads
				(clearance 0)
			)
			(min_thickness 0.25)
			(keepout
				(tracks allowed)
				(vias not_allowed)
				(pads allowed)
				(copperpour not_allowed)
				(footprints allowed)
			)
			(placement
				(enabled no)
				(sheetname "")
			)
			(fill
				(thermal_gap 0.5)
				(thermal_bridge_width 0.5)
				(island_removal_mode 0)
			)
			(polygon
				(pts
					(xy 369.5446 -100.4824) (xy 369.0366 -100.4824) (xy 369.0366 -100.8634) (xy 369.5446 -100.8634)
				)
			)
		)
	)
	(footprint ""
		(layer "F.Cu")
		(at 423.650664 -13.872464 180)
		(property "Reference" "R6W41"
			(at -0.8382 -0.67818 180)
			(unlocked yes)
			(layer "F.SilkS")
			(effects
				(font
					(size 0.4064 0.254)
					(thickness 0.1524)
				)
				(justify left)
			)
		)
		(property "Value" ""
			(at 0 0 180)
			(layer "F.Fab")
			(effects
				(font
					(size 1.27 1.27)
				)
			)
		)
		(duplicate_pad_numbers_are_jumpers no)
		(fp_poly
			(pts
				(xy -0.2794 -0.1016) (xy 0.2794 -0.1016) (xy 0.2794 0.9906) (xy -0.2794 0.9906)
			)
			(stroke
				(width 0)
				(type default)
			)
			(fill no)
			(layer "F.CrtYd")
		)
		(fp_line
			(start 0.2794 0.9906)
			(end 0.2794 -0.1016)
			(stroke
				(width 0.1)
				(type default)
			)
			(layer "F.Fab")
		)
		(fp_line
			(start 0.2794 -0.1016)
			(end -0.2794 -0.1016)
			(stroke
				(width 0.1)
				(type default)
			)
			(layer "F.Fab")
		)
		(fp_line
			(start -0.2794 0.9906)
			(end 0.2794 0.9906)
			(stroke
				(width 0.1)
				(type default)
			)
			(layer "F.Fab")
		)
		(fp_line
			(start -0.2794 -0.1016)
			(end -0.2794 0.9906)
			(stroke
				(width 0.1)
				(type default)
			)
			(layer "F.Fab")
		)
		(pad "1" smd rect
			(at 0 0 180)
			(size 0.508 0.508)
			(layers "F.Cu" "F.Mask" "F.Paste")
			(net "P3V3_STBY")
		)
		(pad "2" smd rect
			(at 0 0.889 180)
			(size 0.508 0.508)
			(layers "F.Cu" "F.Mask" "F.Paste")
			(net "PCA9554_INT_N")
		)
		(zone
			(layer "F.Cu")
			(hatch none 0.5)
			(connect_pads
				(clearance 0)
			)
			(min_thickness 0.25)
			(keepout
				(tracks not_allowed)
				(vias allowed)
				(pads allowed)
				(copperpour not_allowed)
				(footprints allowed)
			)
			(placement
				(enabled no)
				(sheetname "")
			)
			(fill
				(thermal_gap 0.5)
				(thermal_bridge_width 0.5)
				(island_removal_mode 0)
			)
			(polygon
				(pts
					(xy 423.904664 -14.507464) (xy 423.396664 -14.507464) (xy 423.396664 -14.126464) (xy 423.904664 -14.126464)
				)
			)
		)
		(zone
			(layer "F.Cu")
			(hatch none 0.5)
			(connect_pads
				(clearance 0)
			)
			(min_thickness 0.25)
			(keepout
				(tracks allowed)
				(vias not_allowed)
				(pads allowed)
				(copperpour not_allowed)
				(footprints allowed)
			)
			(placement
				(enabled no)
				(sheetname "")
			)
			(fill
				(thermal_gap 0.5)
				(thermal_bridge_width 0.5)
				(island_removal_mode 0)
			)
			(polygon
				(pts
					(xy 423.904664 -14.126464) (xy 423.396664 -14.126464) (xy 423.396664 -14.507464) (xy 423.904664 -14.507464)
				)
			)
		)
	)
	(footprint ""
		(layer "F.Cu")
		(at 386.1054 1.651 -90)
		(property "Reference" "R7G22"
			(at 0 0 270)
			(layer "F.SilkS")
			(hide yes)
			(effects
				(font
					(size 1.27 1.27)
				)
			)
		)
		(property "Value" ""
			(at 0 0 270)
			(layer "F.Fab")
			(effects
				(font
					(size 1.27 1.27)
				)
			)
		)
		(duplicate_pad_numbers_are_jumpers no)
		(fp_poly
			(pts
				(xy -0.2794 -0.1016) (xy 0.2794 -0.1016) (xy 0.2794 0.9906) (xy -0.2794 0.9906)
			)
			(stroke
				(width 0)
				(type default)
			)
			(fill no)
			(layer "F.CrtYd")
		)
		(fp_line
			(start -0.2794 0.9906)
			(end 0.2794 0.9906)
			(stroke
				(width 0.1)
				(type default)
			)
			(layer "F.Fab")
		)
		(fp_line
			(start 0.2794 0.9906)
			(end 0.2794 -0.1016)
			(stroke
				(width 0.1)
				(type default)
			)
			(layer "F.Fab")
		)
		(fp_line
			(start -0.2794 -0.1016)
			(end -0.2794 0.9906)
			(stroke
				(width 0.1)
				(type default)
			)
			(layer "F.Fab")
		)
		(fp_line
			(start 0.2794 -0.1016)
			(end -0.2794 -0.1016)
			(stroke
				(width 0.1)
				(type default)
			)
			(layer "F.Fab")
		)
		(pad "1" smd rect
			(at 0 0 270)
			(size 0.508 0.508)
			(layers "F.Cu" "F.Mask" "F.Paste")
			(net "P3V3_STBY")
		)
		(pad "2" smd rect
			(at 0 0.889 270)
			(size 0.508 0.508)
			(layers "F.Cu" "F.Mask" "F.Paste")
			(net "JTAG_TDO_R")
		)
		(zone
			(layer "F.Cu")
			(hatch none 0.5)
			(connect_pads
				(clearance 0)
			)
			(min_thickness 0.25)
			(keepout
				(tracks not_allowed)
				(vias allowed)
				(pads allowed)
				(copperpour not_allowed)
				(footprints allowed)
			)
			(placement
				(enabled no)
				(sheetname "")
			)
			(fill
				(thermal_gap 0.5)
				(thermal_bridge_width 0.5)
				(island_removal_mode 0)
			)
			(polygon
				(pts
					(xy 385.4704 1.397) (xy 385.4704 1.905) (xy 385.8514 1.905) (xy 385.8514 1.397)
				)
			)
		)
		(zone
			(layer "F.Cu")
			(hatch none 0.5)
			(connect_pads
				(clearance 0)
			)
			(min_thickness 0.25)
			(keepout
				(tracks allowed)
				(vias not_allowed)
				(pads allowed)
				(copperpour not_allowed)
				(footprints allowed)
			)
			(placement
				(enabled no)
				(sheetname "")
			)
			(fill
				(thermal_gap 0.5)
				(thermal_bridge_width 0.5)
				(island_removal_mode 0)
			)
			(polygon
				(pts
					(xy 385.8514 1.397) (xy 385.8514 1.905) (xy 385.4704 1.905) (xy 385.4704 1.397)
				)
			)
		)
	)
)
